(kicad_pcb
	(version 20241229)
	(generator "pcbnew")
	(generator_version "9.0")
	(general
		(thickness 1.61)
		(legacy_teardrops no)
	)
	(paper "A3")
	(title_block
		(title "RDIMM DDR5 Tester")
		(date "2026-05-21")
		(rev "2.2.0")
		(company "Antmicro")
		(comment 9 "footprints 40-40 of 796")
	)
	(layers
		(0 "F.Cu" signal)
		(4 "In1.Cu" power)
		(6 "In2.Cu" mixed)
		(8 "In3.Cu" power)
		(10 "In4.Cu" mixed)
		(12 "In5.Cu" power)
		(14 "In6.Cu" mixed)
		(16 "In7.Cu" power)
		(18 "In8.Cu" power)
		(20 "In9.Cu" mixed)
		(22 "In10.Cu" power)
		(2 "B.Cu" signal)
		(9 "F.Adhes" user "F.Adhesive")
		(11 "B.Adhes" user "B.Adhesive")
		(13 "F.Paste" user)
		(15 "B.Paste" user)
		(5 "F.SilkS" user "F.Silkscreen")
		(7 "B.SilkS" user "B.Silkscreen")
		(1 "F.Mask" user)
		(3 "B.Mask" user)
		(17 "Dwgs.User" user "User.Drawings")
		(19 "Cmts.User" user "User.Comments")
		(21 "Eco1.User" user "User.Eco1")
		(23 "Eco2.User" user "User.Eco2")
		(25 "Edge.Cuts" user)
		(27 "Margin" user)
		(31 "F.CrtYd" user "F.Courtyard")
		(29 "B.CrtYd" user "B.Courtyard")
		(35 "F.Fab" user)
		(33 "B.Fab" user)
	)
	(footprint "antmicro-footprints:QFN-48-1EP_7x7x0.9mm_P0.5mm_EP3.5x3.5mm"
		(layer "F.Cu")
		(at 134.675 143.235 -90)
		(property "Reference" "U15"
			(at 5.114 -2.249499 0)
			(layer "F.SilkS")
			(effects
				(font
					(size 0.7 0.7)
					(thickness 0.15)
				)
				(justify left bottom)
			)
		)
		(property "Value" "KSZ9031RNXCA"
			(at 0 5.1 90)
			(layer "F.Fab")
			(hide yes)
			(effects
				(font
					(size 0.7 0.7)
					(thickness 0.15)
				)
				(justify right bottom)
			)
		)
		(property "Datasheet" "http://ww1.microchip.com/downloads/en/DeviceDoc/00002117F.pdf"
			(at 0 0 270)
			(layer "F.Fab")
			(hide yes)
			(effects
				(font
					(size 1.27 1.27)
					(thickness 0.15)
				)
			)
		)
		(property "Manufacturer" "Microchip Technology"
			(at 0 0 270)
			(unlocked yes)
			(layer "F.Fab")
			(hide yes)
			(effects
				(font
					(size 1 1)
					(thickness 0.15)
				)
			)
		)
		(property "MPN" "KSZ9031RNXCA"
			(at 0 0 270)
			(unlocked yes)
			(layer "F.Fab")
			(hide yes)
			(effects
				(font
					(size 1 1)
					(thickness 0.15)
				)
			)
		)
		(property "Author" "Antmicro"
			(at 0 0 270)
			(unlocked yes)
			(layer "F.Fab")
			(hide yes)
			(effects
				(font
					(size 1 1)
					(thickness 0.15)
				)
			)
		)
		(property "License" "Apache-2.0"
			(at 0 0 270)
			(unlocked yes)
			(layer "F.Fab")
			(hide yes)
			(effects
				(font
					(size 1 1)
					(thickness 0.15)
				)
			)
		)
		(sheetname "/Ethernet/")
		(sheetfile "ethernet.kicad_sch")
		(attr smd)
		(fp_line
			(start -3.65 3.648)
			(end -3.65 3.249)
			(stroke
				(width 0.15)
				(type solid)
			)
			(layer "F.SilkS")
		)
		(fp_line
			(start -3.25 3.648)
			(end -3.65 3.648)
			(stroke
				(width 0.15)
				(type solid)
			)
			(layer "F.SilkS")
		)
		(fp_line
			(start 3.249 3.648)
			(end 3.648 3.648)
			(stroke
				(width 0.15)
				(type solid)
			)
			(layer "F.SilkS")
		)
		(fp_line
			(start 3.648 3.648)
			(end 3.648 3.249)
			(stroke
				(width 0.15)
				(type solid)
			)
			(layer "F.SilkS")
		)
		(fp_line
			(start -3.65 -3.3)
			(end -3.65 -3.65)
			(stroke
				(width 0.15)
				(type solid)
			)
			(layer "F.SilkS")
		)
		(fp_line
			(start -3.3 -3.65)
			(end -3.65 -3.65)
			(stroke
				(width 0.15)
				(type solid)
			)
			(layer "F.SilkS")
		)
		(fp_line
			(start 3.249 -3.65)
			(end 3.648 -3.65)
			(stroke
				(width 0.15)
				(type solid)
			)
			(layer "F.SilkS")
		)
		(fp_line
			(start 3.648 -3.65)
			(end 3.648 -3.25)
			(stroke
				(width 0.15)
				(type solid)
			)
			(layer "F.SilkS")
		)
		(fp_circle
			(center -3.7 -3.05)
			(end -3.65 -3.05)
			(stroke
				(width 0.15)
				(type solid)
			)
			(fill yes)
			(layer "F.SilkS")
		)
		(fp_rect
			(start -4.15 -4.15)
			(end 4.15 4.15)
			(stroke
				(width 0.05)
				(type solid)
			)
			(fill no)
			(layer "F.CrtYd")
		)
		(fp_line
			(start -3.5 3.499)
			(end 3.499 3.499)
			(stroke
				(width 0.15)
				(type solid)
			)
			(layer "F.Fab")
		)
		(fp_line
			(start 3.499 3.499)
			(end 3.499 -3.5)
			(stroke
				(width 0.15)
				(type solid)
			)
			(layer "F.Fab")
		)
		(fp_line
			(start -3.5 -2.5)
			(end -3.5 3.499)
			(stroke
				(width 0.15)
				(type solid)
			)
			(layer "F.Fab")
		)
		(fp_line
			(start -2.5 -3.5)
			(end -3.5 -2.5)
			(stroke
				(width 0.15)
				(type solid)
			)
			(layer "F.Fab")
		)
		(fp_line
			(start 3.499 -3.5)
			(end -2.5 -3.5)
			(stroke
				(width 0.15)
				(type solid)
			)
			(layer "F.Fab")
		)
		(fp_text user "Author: Antmicro"
			(at -4.202 8.4 270)
			(layer "F.Fab")
			(effects
				(font
					(size 0.7 0.7)
					(thickness 0.15)
				)
				(justify left bottom)
			)
		)
		(fp_text user "License: Apache-2.0"
			(at -4.202 9.598 270)
			(layer "F.Fab")
			(effects
				(font
					(size 0.7 0.7)
					(thickness 0.15)
				)
				(justify left bottom)
			)
		)
		(fp_text user "${REFERENCE}"
			(at -4.202 7.2 270)
			(layer "F.Fab")
			(effects
				(font
					(size 0.7 0.7)
					(thickness 0.15)
				)
				(justify left bottom)
			)
		)
		(pad "1" smd oval
			(at -3.5 -2.75)
			(size 0.3 0.9)
			(layers "F.Cu" "F.Mask" "F.Paste")
			(net 97 "/Ethernet/AVDDH")
			(pinfunction "AVDDH")
			(pintype "power_in")
		)
		(pad "2" smd oval
			(at -3.5 -2.25)
			(size 0.3 0.9)
			(layers "F.Cu" "F.Mask" "F.Paste")
			(net 88 "/Ethernet/ETH1_P")
			(pinfunction "TXRXP_A")
			(pintype "bidirectional")
		)
		(pad "3" smd oval
			(at -3.5 -1.75)
			(size 0.3 0.9)
			(layers "F.Cu" "F.Mask" "F.Paste")
			(net 91 "/Ethernet/ETH1_N")
			(pinfunction "TXRXM_A")
			(pintype "bidirectional")
		)
		(pad "4" smd oval
			(at -3.5 -1.25)
			(size 0.3 0.9)
			(layers "F.Cu" "F.Mask" "F.Paste")
			(net 95 "/Ethernet/AVDDL")
			(pinfunction "AVDDL")
			(pintype "power_in")
		)
		(pad "5" smd oval
			(at -3.5 -0.75)
			(size 0.3 0.9)
			(layers "F.Cu" "F.Mask" "F.Paste")
			(net 87 "/Ethernet/ETH2_P")
			(pinfunction "TXRXP_B")
			(pintype "bidirectional")
		)
		(pad "6" smd oval
			(at -3.5 -0.25)
			(size 0.3 0.9)
			(layers "F.Cu" "F.Mask" "F.Paste")
			(net 90 "/Ethernet/ETH2_N")
			(pinfunction "TXRXM_B")
			(pintype "bidirectional")
		)
		(pad "7" smd oval
			(at -3.5 0.248)
			(size 0.3 0.9)
			(layers "F.Cu" "F.Mask" "F.Paste")
			(net 86 "/Ethernet/ETH3_P")
			(pinfunction "TXRXP_C")
			(pintype "bidirectional")
		)
		(pad "8" smd oval
			(at -3.5 0.748)
			(size 0.3 0.9)
			(layers "F.Cu" "F.Mask" "F.Paste")
			(net 92 "/Ethernet/ETH3_N")
			(pinfunction "TXRXM_C")
			(pintype "bidirectional")
		)
		(pad "9" smd oval
			(at -3.5 1.249)
			(size 0.3 0.9)
			(layers "F.Cu" "F.Mask" "F.Paste")
			(net 95 "/Ethernet/AVDDL")
			(pinfunction "AVDDL")
			(pintype "passive")
		)
		(pad "10" smd oval
			(at -3.5 1.749)
			(size 0.3 0.9)
			(layers "F.Cu" "F.Mask" "F.Paste")
			(net 89 "/Ethernet/ETH4_P")
			(pinfunction "TXRXP_D")
			(pintype "bidirectional")
		)
		(pad "11" smd oval
			(at -3.5 2.249)
			(size 0.3 0.9)
			(layers "F.Cu" "F.Mask" "F.Paste")
			(net 93 "/Ethernet/ETH4_N")
			(pinfunction "TXRXM_D")
			(pintype "bidirectional")
		)
		(pad "12" smd oval
			(at -3.5 2.749)
			(size 0.3 0.9)
			(layers "F.Cu" "F.Mask" "F.Paste")
			(net 97 "/Ethernet/AVDDH")
			(pinfunction "AVDDH")
			(pintype "passive")
		)
		(pad "13" smd oval
			(at -2.75 3.499 270)
			(size 0.3 0.9)
			(layers "F.Cu" "F.Mask" "F.Paste")
			(net 425 "unconnected-(U15-NC-Pad13)")
			(pinfunction "NC")
			(pintype "no_connect")
		)
		(pad "14" smd oval
			(at -2.25 3.499 270)
			(size 0.3 0.9)
			(layers "F.Cu" "F.Mask" "F.Paste")
			(net 150 "+1V2")
			(pinfunction "DVDDL")
			(pintype "power_in")
		)
		(pad "15" smd oval
			(at -1.75 3.499 270)
			(size 0.3 0.9)
			(layers "F.Cu" "F.Mask" "F.Paste")
			(net 330 "/Ethernet/LED_SPD")
			(pinfunction "LED2/PHYAD1")
			(pintype "bidirectional")
		)
		(pad "16" smd oval
			(at -1.25 3.499 270)
			(size 0.3 0.9)
			(layers "F.Cu" "F.Mask" "F.Paste")
			(net 797 "+1V8")
			(pinfunction "DVDDH")
			(pintype "power_in")
		)
		(pad "17" smd oval
			(at -0.75 3.499 270)
			(size 0.3 0.9)
			(layers "F.Cu" "F.Mask" "F.Paste")
			(net 331 "/Ethernet/LED_LINK")
			(pinfunction "LED1/PHYAD0/PME_N1")
			(pintype "bidirectional")
		)
		(pad "18" smd oval
			(at -0.25 3.499 270)
			(size 0.3 0.9)
			(layers "F.Cu" "F.Mask" "F.Paste")
			(net 150 "+1V2")
			(pinfunction "DVDDL")
			(pintype "passive")
		)
		(pad "19" smd oval
			(at 0.248 3.499 270)
			(size 0.3 0.9)
			(layers "F.Cu" "F.Mask" "F.Paste")
			(net 436 "/Ethernet/ETH.TXD0")
			(pinfunction "TXD0")
			(pintype "input")
		)
		(pad "20" smd oval
			(at 0.748 3.499 270)
			(size 0.3 0.9)
			(layers "F.Cu" "F.Mask" "F.Paste")
			(net 440 "/Ethernet/ETH.TXD1")
			(pinfunction "TXD1")
			(pintype "input")
		)
		(pad "21" smd oval
			(at 1.249 3.499 270)
			(size 0.3 0.9)
			(layers "F.Cu" "F.Mask" "F.Paste")
			(net 439 "/Ethernet/ETH.TXD2")
			(pinfunction "TXD2")
			(pintype "input")
		)
		(pad "22" smd oval
			(at 1.749 3.499 270)
			(size 0.3 0.9)
			(layers "F.Cu" "F.Mask" "F.Paste")
			(net 438 "/Ethernet/ETH.TXD3")
			(pinfunction "TXD3")
			(pintype "input")
		)
		(pad "23" smd oval
			(at 2.249 3.499 270)
			(size 0.3 0.9)
			(layers "F.Cu" "F.Mask" "F.Paste")
			(net 150 "+1V2")
			(pinfunction "DVDDL")
			(pintype "passive")
		)
		(pad "24" smd oval
			(at 2.749 3.499 270)
			(size 0.3 0.9)
			(layers "F.Cu" "F.Mask" "F.Paste")
			(net 409 "/Ethernet/ETH.TXC")
			(pinfunction "GTX_CLK")
			(pintype "input")
		)
		(pad "25" smd oval
			(at 3.499 2.749)
			(size 0.3 0.9)
			(layers "F.Cu" "F.Mask" "F.Paste")
			(net 435 "/Ethernet/ETH.TX_CTL")
			(pinfunction "TX_EN")
			(pintype "input")
		)
		(pad "26" smd oval
			(at 3.499 2.249)
			(size 0.3 0.9)
			(layers "F.Cu" "F.Mask" "F.Paste")
			(net 150 "+1V2")
			(pinfunction "DVDDL")
			(pintype "passive")
		)
		(pad "27" smd oval
			(at 3.499 1.749)
			(size 0.3 0.9)
			(layers "F.Cu" "F.Mask" "F.Paste")
			(net 396 "/Ethernet/ETH.RXD3")
			(pinfunction "RXD3/MODE3")
			(pintype "input")
		)
		(pad "28" smd oval
			(at 3.499 1.249)
			(size 0.3 0.9)
			(layers "F.Cu" "F.Mask" "F.Paste")
			(net 395 "/Ethernet/ETH.RXD2")
			(pinfunction "RXD2/MODE2")
			(pintype "input")
		)
		(pad "29" smd oval
			(at 3.499 0.748)
			(size 0.3 0.9)
			(layers "F.Cu" "F.Mask" "F.Paste")
			(net 1 "GND")
			(pinfunction "VSS")
			(pintype "power_in")
		)
		(pad "30" smd oval
			(at 3.499 0.248)
			(size 0.3 0.9)
			(layers "F.Cu" "F.Mask" "F.Paste")
			(net 150 "+1V2")
			(pinfunction "DVDDL")
			(pintype "passive")
		)
		(pad "31" smd oval
			(at 3.499 -0.25)
			(size 0.3 0.9)
			(layers "F.Cu" "F.Mask" "F.Paste")
			(net 394 "/Ethernet/ETH.RXD1")
			(pinfunction "RXD1/MODE1")
			(pintype "input")
		)
		(pad "32" smd oval
			(at 3.499 -0.75)
			(size 0.3 0.9)
			(layers "F.Cu" "F.Mask" "F.Paste")
			(net 393 "/Ethernet/ETH.RXD0")
			(pinfunction "RXD0/MODE0")
			(pintype "input")
		)
		(pad "33" smd oval
			(at 3.499 -1.25)
			(size 0.3 0.9)
			(layers "F.Cu" "F.Mask" "F.Paste")
			(net 397 "/Ethernet/ETH.RX_CTL")
			(pinfunction "RX_DV/CLK125_EN")
			(pintype "input")
		)
		(pad "34" smd oval
			(at 3.499 -1.75)
			(size 0.3 0.9)
			(layers "F.Cu" "F.Mask" "F.Paste")
			(net 797 "+1V8")
			(pinfunction "DVDDH")
			(pintype "passive")
		)
		(pad "35" smd oval
			(at 3.499 -2.25)
			(size 0.3 0.9)
			(layers "F.Cu" "F.Mask" "F.Paste")
			(net 398 "/Ethernet/ETH.RXC")
			(pinfunction "RX_CLK/PHYAD2")
			(pintype "input")
		)
		(pad "36" smd oval
			(at 3.499 -2.75)
			(size 0.3 0.9)
			(layers "F.Cu" "F.Mask" "F.Paste")
			(net 410 "/Ethernet/ETH.MDC")
			(pinfunction "MDC")
			(pintype "input")
		)
		(pad "37" smd oval
			(at 2.749 -3.5 270)
			(size 0.3 0.9)
			(layers "F.Cu" "F.Mask" "F.Paste")
			(net 400 "/Ethernet/ETH.MDIO")
			(pinfunction "MDIO")
			(pintype "input")
		)
		(pad "38" smd oval
			(at 2.249 -3.5 270)
			(size 0.3 0.9)
			(layers "F.Cu" "F.Mask" "F.Paste")
			(net 437 "/Ethernet/ETH.~{INT}")
			(pinfunction "~{INT/PME}")
			(pintype "input")
		)
		(pad "39" smd oval
			(at 1.749 -3.5 270)
			(size 0.3 0.9)
			(layers "F.Cu" "F.Mask" "F.Paste")
			(net 150 "+1V2")
			(pinfunction "DVDDL")
			(pintype "passive")
		)
		(pad "40" smd oval
			(at 1.249 -3.5 270)
			(size 0.3 0.9)
			(layers "F.Cu" "F.Mask" "F.Paste")
			(net 797 "+1V8")
			(pinfunction "DVDDH")
			(pintype "passive")
		)
		(pad "41" smd oval
			(at 0.748 -3.5 270)
			(size 0.3 0.9)
			(layers "F.Cu" "F.Mask" "F.Paste")
			(net 399 "/Ethernet/ETH.REF_CLK")
			(pinfunction "CLK125_NDO/LED_MODE")
			(pintype "input")
		)
		(pad "42" smd oval
			(at 0.248 -3.5 270)
			(size 0.3 0.9)
			(layers "F.Cu" "F.Mask" "F.Paste")
			(net 401 "/Ethernet/ETH.~{RESET}")
			(pinfunction "~{RESET}")
			(pintype "input")
		)
		(pad "43" smd oval
			(at -0.25 -3.5 270)
			(size 0.3 0.9)
			(layers "F.Cu" "F.Mask" "F.Paste")
			(net 426 "unconnected-(U15-LDO_O-Pad43)")
			(pinfunction "LDO_O")
			(pintype "input+no_connect")
		)
		(pad "44" smd oval
			(at -0.75 -3.5 270)
			(size 0.3 0.9)
			(layers "F.Cu" "F.Mask" "F.Paste")
			(net 96 "/Ethernet/AVDDL_PLL")
			(pinfunction "AVDDL_PLL")
			(pintype "power_in")
		)
		(pad "45" smd oval
			(at -1.25 -3.5 270)
			(size 0.3 0.9)
			(layers "F.Cu" "F.Mask" "F.Paste")
			(net 228 "Net-(U15-XO)")
			(pinfunction "XO")
			(pintype "input")
		)
		(pad "46" smd oval
			(at -1.75 -3.5 270)
			(size 0.3 0.9)
			(layers "F.Cu" "F.Mask" "F.Paste")
			(net 227 "Net-(U15-XI)")
			(pinfunction "XI")
			(pintype "input")
		)
		(pad "47" smd oval
			(at -2.25 -3.5 270)
			(size 0.3 0.9)
			(layers "F.Cu" "F.Mask" "F.Paste")
			(net 427 "unconnected-(U15-NC-Pad47)")
			(pinfunction "NC")
			(pintype "no_connect")
		)
		(pad "48" smd oval
			(at -2.75 -3.5 270)
			(size 0.3 0.9)
			(layers "F.Cu" "F.Mask" "F.Paste")
			(net 302 "Net-(U15-ISET)")
			(pinfunction "ISET")
			(pintype "output")
		)
		(pad "49" smd rect
			(at 0 0 270)
			(size 3.5 3.5)
			(layers "F.Cu" "F.Mask" "F.Paste")
			(net 1 "GND")
			(pinfunction "PAD_GND")
			(pintype "power_in")
		)
	)
)
